(kicad_pcb
	(version 20241229)
	(generator "pcbnew")
	(generator_version "9.0")
	(general
		(thickness 1.6296)
		(legacy_teardrops no)
	)
	(paper "A3")
	(title_block
		(title "Thunderbolt to 10GbE adapter")
		(date "2026-04-21")
		(rev "1.1.0")
		(company "Antmicro Ltd")
		(comment 1 "www.antmicro.com")
		(comment 9 "footprints 686-689 of 703")
	)
	(layers
		(0 "F.Cu" signal)
		(4 "In1.Cu" signal)
		(6 "In2.Cu" signal)
		(8 "In3.Cu" signal)
		(10 "In4.Cu" signal)
		(12 "In5.Cu" signal)
		(14 "In6.Cu" signal)
		(2 "B.Cu" signal)
		(9 "F.Adhes" user "F.Adhesive")
		(11 "B.Adhes" user "B.Adhesive")
		(13 "F.Paste" user)
		(15 "B.Paste" user)
		(5 "F.SilkS" user "F.Silkscreen")
		(7 "B.SilkS" user "B.Silkscreen")
		(1 "F.Mask" user)
		(3 "B.Mask" user)
		(17 "Dwgs.User" user "User.Drawings")
		(19 "Cmts.User" user "User.Comments")
		(21 "Eco1.User" user "User.Eco1")
		(23 "Eco2.User" user "User.Eco2")
		(25 "Edge.Cuts" user)
		(27 "Margin" user)
		(31 "F.CrtYd" user "F.Courtyard")
		(29 "B.CrtYd" user "B.Courtyard")
		(35 "F.Fab" user)
		(33 "B.Fab" user)
	)
	(footprint "antmicro-footprints:C_0402_1005Metric"
		(layer "B.Cu")
		(at 153.031866 75.260117 180)
		(descr "Capacitor SMD 0402")
		(tags "capacitor SMD 0402")
		(property "Reference" "C225"
			(at -21.168135 -9.464883 0)
			(layer "B.SilkS")
			(effects
				(font
					(size 0.7 0.7)
					(thickness 0.15)
				)
				(justify mirror)
			)
		)
		(property "Value" "C_1u_25V_0402"
			(at -1.022927 -2.155213 0)
			(layer "B.Fab")
			(effects
				(font
					(size 0.7 0.7)
					(thickness 0.15)
				)
				(justify left bottom mirror)
			)
		)
		(property "Datasheet" "https://www.murata.com/products/productdetail?partno=GRM155R61E105KE11%23"
			(at 0 0 0)
			(layer "B.Fab")
			(hide yes)
			(effects
				(font
					(size 1.27 1.27)
					(thickness 0.15)
				)
				(justify mirror)
			)
		)
		(property "Description" "SMD Multilayer Ceramic Capacitor, 1 µF, 25 V, 0402 [1005 Metric], ± 10%, X5R, GRM Series"
			(at 0 0 0)
			(layer "B.Fab")
			(hide yes)
			(effects
				(font
					(size 1.27 1.27)
					(thickness 0.15)
				)
				(justify mirror)
			)
		)
		(property "MPN" "GRM155R61E105KE11J"
			(at 0 0 180)
			(unlocked yes)
			(layer "B.Fab")
			(hide yes)
			(effects
				(font
					(size 1 1)
					(thickness 0.15)
				)
				(justify mirror)
			)
		)
		(property "Manufacturer" "Murata"
			(at 0 0 180)
			(unlocked yes)
			(layer "B.Fab")
			(hide yes)
			(effects
				(font
					(size 1 1)
					(thickness 0.15)
				)
				(justify mirror)
			)
		)
		(property "License" "Apache-2.0"
			(at 0 0 180)
			(unlocked yes)
			(layer "B.Fab")
			(hide yes)
			(effects
				(font
					(size 1 1)
					(thickness 0.15)
				)
				(justify mirror)
			)
		)
		(property "Author" "Antmicro"
			(at 0 0 180)
			(unlocked yes)
			(layer "B.Fab")
			(hide yes)
			(effects
				(font
					(size 1 1)
					(thickness 0.15)
				)
				(justify mirror)
			)
		)
		(property "Val" "1u"
			(at 0 0 180)
			(unlocked yes)
			(layer "B.Fab")
			(hide yes)
			(effects
				(font
					(size 1 1)
					(thickness 0.15)
				)
				(justify mirror)
			)
		)
		(property "Voltage" "25V"
			(at 0 0 180)
			(unlocked yes)
			(layer "B.Fab")
			(hide yes)
			(effects
				(font
					(size 1 1)
					(thickness 0.15)
				)
				(justify mirror)
			)
		)
		(property "Dielectric" "X5R"
			(at 0 0 180)
			(unlocked yes)
			(layer "B.Fab")
			(hide yes)
			(effects
				(font
					(size 1 1)
					(thickness 0.15)
				)
				(justify mirror)
			)
		)
		(sheetname "/X710-AT2 power/")
		(sheetfile "x710-at2-power.kicad_sch")
		(attr smd)
		(fp_rect
			(start -0.925 0.47)
			(end 0.925 -0.47)
			(stroke
				(width 0.05)
				(type default)
			)
			(fill no)
			(layer "B.CrtYd")
		)
		(fp_line
			(start 0.504 0.25)
			(end 0.504 -0.248)
			(stroke
				(width 0.15)
				(type solid)
			)
			(layer "B.Fab")
		)
		(fp_line
			(start 0.504 -0.248)
			(end -0.494 -0.248)
			(stroke
				(width 0.15)
				(type solid)
			)
			(layer "B.Fab")
		)
		(fp_line
			(start -0.494 0.25)
			(end 0.504 0.25)
			(stroke
				(width 0.15)
				(type solid)
			)
			(layer "B.Fab")
		)
		(fp_line
			(start -0.494 -0.248)
			(end -0.494 0.25)
			(stroke
				(width 0.15)
				(type solid)
			)
			(layer "B.Fab")
		)
		(fp_text user "${REFERENCE}"
			(at -0.939 -4.599 0)
			(layer "B.Fab")
			(effects
				(font
					(size 0.7 0.7)
					(thickness 0.15)
				)
				(justify left bottom mirror)
			)
		)
		(fp_text user "License: Apache-2.0"
			(at -0.939 -5.799 0)
			(layer "B.Fab")
			(effects
				(font
					(size 0.7 0.7)
					(thickness 0.15)
				)
				(justify left bottom mirror)
			)
		)
		(fp_text user "Author: Antmicro"
			(at -0.939 -3.399 0)
			(layer "B.Fab")
			(effects
				(font
					(size 0.7 0.7)
					(thickness 0.15)
				)
				(justify left bottom mirror)
			)
		)
		(pad "1" smd roundrect
			(at -0.48 0 180)
			(size 0.59 0.64)
			(layers "B.Cu" "B.Mask" "B.Paste")
			(roundrect_rratio 0.25)
			(net 23 "GND")
			(pintype "passive")
		)
		(pad "2" smd roundrect
			(at 0.48 0 180)
			(size 0.59 0.64)
			(layers "B.Cu" "B.Mask" "B.Paste")
			(roundrect_rratio 0.25)
			(net 7 "+3V3")
			(pintype "passive")
		)
	)
	(footprint "antmicro-footprints:C_1206_3216Metric"
		(layer "B.Cu")
		(at 163.25 136.25 90)
		(descr "Capacitor SMD 1206")
		(tags "capacitor SMD 1206")
		(property "Reference" "C291"
			(at 1.25 -1.25 270)
			(layer "B.SilkS")
			(effects
				(font
					(size 0.7 0.7)
					(thickness 0.15)
				)
				(justify left bottom mirror)
			)
		)
		(property "Value" "C_220u_1206_6V3"
			(at 0 -2.101 270)
			(layer "B.Fab")
			(effects
				(font
					(size 0.7 0.7)
					(thickness 0.15)
				)
				(justify left bottom mirror)
			)
		)
		(property "Datasheet" "https://www.murata.com/products/productdetail?partno=GRM31CR60J227ME11%23"
			(at 0 0 270)
			(layer "B.Fab")
			(hide yes)
			(effects
				(font
					(size 1.27 1.27)
					(thickness 0.15)
				)
				(justify mirror)
			)
		)
		(property "Description" "SMD Multilayer Ceramic Capacitor, 220 µF, 6.3 V, 1206 [3216 Metric], ± 20%, X5R, GRM Series"
			(at 0 0 270)
			(layer "B.Fab")
			(hide yes)
			(effects
				(font
					(size 1.27 1.27)
					(thickness 0.15)
				)
				(justify mirror)
			)
		)
		(property "MPN" "GRM31CR60J227ME11L"
			(at 0 0 90)
			(unlocked yes)
			(layer "B.Fab")
			(hide yes)
			(effects
				(font
					(size 1 1)
					(thickness 0.15)
				)
				(justify mirror)
			)
		)
		(property "Manufacturer" "Murata"
			(at 0 0 90)
			(unlocked yes)
			(layer "B.Fab")
			(hide yes)
			(effects
				(font
					(size 1 1)
					(thickness 0.15)
				)
				(justify mirror)
			)
		)
		(property "License" "Apache-2.0"
			(at 0 0 90)
			(unlocked yes)
			(layer "B.Fab")
			(hide yes)
			(effects
				(font
					(size 1 1)
					(thickness 0.15)
				)
				(justify mirror)
			)
		)
		(property "Author" "Antmicro"
			(at 0 0 90)
			(unlocked yes)
			(layer "B.Fab")
			(hide yes)
			(effects
				(font
					(size 1 1)
					(thickness 0.15)
				)
				(justify mirror)
			)
		)
		(property "Val" "220u"
			(at 0 0 90)
			(unlocked yes)
			(layer "B.Fab")
			(hide yes)
			(effects
				(font
					(size 1 1)
					(thickness 0.15)
				)
				(justify mirror)
			)
		)
		(property "Voltage" ""
			(at 0 0 90)
			(unlocked yes)
			(layer "B.Fab")
			(hide yes)
			(effects
				(font
					(size 1 1)
					(thickness 0.15)
				)
				(justify mirror)
			)
		)
		(property "Dielectric" ""
			(at 0 0 90)
			(unlocked yes)
			(layer "B.Fab")
			(hide yes)
			(effects
				(font
					(size 1 1)
					(thickness 0.15)
				)
				(justify mirror)
			)
		)
		(property "Public" "False"
			(at 0 0 90)
			(unlocked yes)
			(layer "B.Fab")
			(hide yes)
			(effects
				(font
					(size 1 1)
					(thickness 0.15)
				)
				(justify mirror)
			)
		)
		(sheetname "/2xRJ45/")
		(sheetfile "2xrj45.kicad_sch")
		(attr smd)
		(fp_line
			(start 0.8 -0.901)
			(end -0.8 -0.901)
			(stroke
				(width 0.15)
				(type solid)
			)
			(layer "B.SilkS")
		)
		(fp_line
			(start 0.8 0.899)
			(end -0.8 0.899)
			(stroke
				(width 0.15)
				(type solid)
			)
			(layer "B.SilkS")
		)
		(fp_rect
			(start -2.325 1.15)
			(end 2.325 -1.15)
			(stroke
				(width 0.05)
				(type default)
			)
			(fill no)
			(layer "B.CrtYd")
		)
		(fp_rect
			(start -1.6 0.799)
			(end 1.6 -0.801)
			(stroke
				(width 0.15)
				(type solid)
			)
			(fill no)
			(layer "B.Fab")
		)
		(fp_text user "License: Apache-2.0"
			(at -2.625 -6.501 270)
			(layer "B.Fab")
			(effects
				(font
					(size 0.7 0.7)
					(thickness 0.15)
				)
				(justify left bottom mirror)
			)
		)
		(fp_text user "Author: Antmicro"
			(at -2.625 -5.301 270)
			(layer "B.Fab")
			(effects
				(font
					(size 0.7 0.7)
					(thickness 0.15)
				)
				(justify left bottom mirror)
			)
		)
		(fp_text user "${REFERENCE}"
			(at -2.625 -4.101 270)
			(layer "B.Fab")
			(effects
				(font
					(size 0.7 0.7)
					(thickness 0.15)
				)
				(justify left bottom mirror)
			)
		)
		(pad "1" smd roundrect
			(at -1.5 -0.001 90)
			(size 1.15 1.8)
			(layers "B.Cu" "B.Mask" "B.Paste")
			(roundrect_rratio 0.25)
			(net 23 "GND")
			(pintype "passive")
		)
		(pad "2" smd roundrect
			(at 1.5 -0.001 90)
			(size 1.15 1.8)
			(layers "B.Cu" "B.Mask" "B.Paste")
			(roundrect_rratio 0.25)
			(net 135 "+1V88_CT")
			(pintype "passive")
		)
	)
	(footprint "antmicro-footprints:C_0603_1608Metric"
		(layer "B.Cu")
		(at 149.481866 97.5 180)
		(descr "Capacitor SMD 0603")
		(tags "capacitor 0603")
		(property "Reference" "C176"
			(at -1.318134 0.7 0)
			(layer "B.SilkS")
			(effects
				(font
					(size 0.7 0.7)
					(thickness 0.15)
				)
				(justify left bottom mirror)
			)
		)
		(property "Value" "C_10u_10V_X7R_0603"
			(at -1.42757 -1.770288 0)
			(layer "B.Fab")
			(effects
				(font
					(size 0.7 0.7)
					(thickness 0.15)
				)
				(justify left bottom mirror)
			)
		)
		(property "Datasheet" "https://www.murata.com/products/productdetail?partno=GRM188Z71A106KA73%23"
			(at 0 0 0)
			(layer "B.Fab")
			(hide yes)
			(effects
				(font
					(size 1.27 1.27)
					(thickness 0.15)
				)
				(justify mirror)
			)
		)
		(property "Description" "SMD Multilayer Ceramic Capacitor,  10µF, 10V, 0603, ±10%, X7R"
			(at 0 0 0)
			(layer "B.Fab")
			(hide yes)
			(effects
				(font
					(size 1.27 1.27)
					(thickness 0.15)
				)
				(justify mirror)
			)
		)
		(property "MPN" "GRM188Z71A106KA73D"
			(at 0 0 180)
			(unlocked yes)
			(layer "B.Fab")
			(hide yes)
			(effects
				(font
					(size 1 1)
					(thickness 0.15)
				)
				(justify mirror)
			)
		)
		(property "Val" "10u"
			(at 0 0 180)
			(unlocked yes)
			(layer "B.Fab")
			(hide yes)
			(effects
				(font
					(size 1 1)
					(thickness 0.15)
				)
				(justify mirror)
			)
		)
		(property "Voltage" "10V"
			(at 0 0 180)
			(unlocked yes)
			(layer "B.Fab")
			(hide yes)
			(effects
				(font
					(size 1 1)
					(thickness 0.15)
				)
				(justify mirror)
			)
		)
		(property "Dielectric" "X7R"
			(at 0 0 180)
			(unlocked yes)
			(layer "B.Fab")
			(hide yes)
			(effects
				(font
					(size 1 1)
					(thickness 0.15)
				)
				(justify mirror)
			)
		)
		(property "Manufacturer" "Murata"
			(at 0 0 180)
			(unlocked yes)
			(layer "B.Fab")
			(hide yes)
			(effects
				(font
					(size 1 1)
					(thickness 0.15)
				)
				(justify mirror)
			)
		)
		(property "License" "Apache-2.0"
			(at 0 0 180)
			(unlocked yes)
			(layer "B.Fab")
			(hide yes)
			(effects
				(font
					(size 1 1)
					(thickness 0.15)
				)
				(justify mirror)
			)
		)
		(property "Author" "Antmicro"
			(at 0 0 180)
			(unlocked yes)
			(layer "B.Fab")
			(hide yes)
			(effects
				(font
					(size 1 1)
					(thickness 0.15)
				)
				(justify mirror)
			)
		)
		(sheetname "/X710-AT2 power/")
		(sheetfile "x710-at2-power.kicad_sch")
		(attr smd)
		(fp_line
			(start -0.15 0.4)
			(end 0.15 0.4)
			(stroke
				(width 0.15)
				(type solid)
			)
			(layer "B.SilkS")
		)
		(fp_line
			(start -0.15 -0.4)
			(end 0.15 -0.4)
			(stroke
				(width 0.15)
				(type solid)
			)
			(layer "B.SilkS")
		)
		(fp_rect
			(start -1.25 0.65)
			(end 1.25 -0.65)
			(stroke
				(width 0.05)
				(type solid)
			)
			(fill no)
			(layer "B.CrtYd")
		)
		(fp_rect
			(start -0.8 0.4)
			(end 0.8 -0.4)
			(stroke
				(width 0.15)
				(type solid)
			)
			(fill no)
			(layer "B.Fab")
		)
		(fp_text user "Author: Antmicro"
			(at -1.682 -4.894 0)
			(layer "B.Fab")
			(effects
				(font
					(size 0.7 0.7)
					(thickness 0.15)
				)
				(justify left bottom mirror)
			)
		)
		(fp_text user "${REFERENCE}"
			(at -1.682 -3.895 0)
			(layer "B.Fab")
			(effects
				(font
					(size 0.7 0.7)
					(thickness 0.15)
				)
				(justify left bottom mirror)
			)
		)
		(fp_text user "License: Apache-2.0"
			(at -1.682 -5.895 0)
			(layer "B.Fab")
			(effects
				(font
					(size 0.7 0.7)
					(thickness 0.15)
				)
				(justify left bottom mirror)
			)
		)
		(pad "1" smd roundrect
			(at -0.7 0 180)
			(size 0.8 1)
			(layers "B.Cu" "B.Mask" "B.Paste")
			(roundrect_rratio 0.2)
			(net 23 "GND")
			(pintype "passive")
		)
		(pad "2" smd roundrect
			(at 0.7 0 180)
			(size 0.8 1)
			(layers "B.Cu" "B.Mask" "B.Paste")
			(roundrect_rratio 0.2)
			(net 18 "+1V88")
			(pintype "passive")
		)
	)
	(footprint "antmicro-footprints:C_0402_1005Metric"
		(layer "B.Cu")
		(at 167 136)
		(descr "Capacitor SMD 0402")
		(tags "capacitor SMD 0402")
		(property "Reference" "C299"
			(at 1 -0.5 180)
			(layer "B.SilkS")
			(effects
				(font
					(size 0.7 0.7)
					(thickness 0.15)
				)
				(justify left bottom mirror)
			)
		)
		(property "Value" "C_1u_25V_0402"
			(at -1.022927 -2.155213 180)
			(layer "B.Fab")
			(effects
				(font
					(size 0.7 0.7)
					(thickness 0.15)
				)
				(justify left bottom mirror)
			)
		)
		(property "Datasheet" "https://www.murata.com/products/productdetail?partno=GRM155R61E105KE11%23"
			(at 0 0 180)
			(layer "B.Fab")
			(hide yes)
			(effects
				(font
					(size 1.27 1.27)
					(thickness 0.15)
				)
				(justify mirror)
			)
		)
		(property "Description" "SMD Multilayer Ceramic Capacitor, 1 µF, 25 V, 0402 [1005 Metric], ± 10%, X5R, GRM Series"
			(at 0 0 180)
			(layer "B.Fab")
			(hide yes)
			(effects
				(font
					(size 1.27 1.27)
					(thickness 0.15)
				)
				(justify mirror)
			)
		)
		(property "MPN" "GRM155R61E105KE11J"
			(at 0 0 0)
			(unlocked yes)
			(layer "B.Fab")
			(hide yes)
			(effects
				(font
					(size 1 1)
					(thickness 0.15)
				)
				(justify mirror)
			)
		)
		(property "Manufacturer" "Murata"
			(at 0 0 0)
			(unlocked yes)
			(layer "B.Fab")
			(hide yes)
			(effects
				(font
					(size 1 1)
					(thickness 0.15)
				)
				(justify mirror)
			)
		)
		(property "License" "Apache-2.0"
			(at 0 0 0)
			(unlocked yes)
			(layer "B.Fab")
			(hide yes)
			(effects
				(font
					(size 1 1)
					(thickness 0.15)
				)
				(justify mirror)
			)
		)
		(property "Author" "Antmicro"
			(at 0 0 0)
			(unlocked yes)
			(layer "B.Fab")
			(hide yes)
			(effects
				(font
					(size 1 1)
					(thickness 0.15)
				)
				(justify mirror)
			)
		)
		(property "Val" "1u"
			(at 0 0 0)
			(unlocked yes)
			(layer "B.Fab")
			(hide yes)
			(effects
				(font
					(size 1 1)
					(thickness 0.15)
				)
				(justify mirror)
			)
		)
		(property "Voltage" "25V"
			(at 0 0 0)
			(unlocked yes)
			(layer "B.Fab")
			(hide yes)
			(effects
				(font
					(size 1 1)
					(thickness 0.15)
				)
				(justify mirror)
			)
		)
		(property "Dielectric" "X5R"
			(at 0 0 0)
			(unlocked yes)
			(layer "B.Fab")
			(hide yes)
			(effects
				(font
					(size 1 1)
					(thickness 0.15)
				)
				(justify mirror)
			)
		)
		(sheetname "/2xRJ45/")
		(sheetfile "2xrj45.kicad_sch")
		(attr smd)
		(fp_rect
			(start -0.925 0.47)
			(end 0.925 -0.47)
			(stroke
				(width 0.05)
				(type default)
			)
			(fill no)
			(layer "B.CrtYd")
		)
		(fp_line
			(start -0.494 -0.248)
			(end -0.494 0.25)
			(stroke
				(width 0.15)
				(type solid)
			)
			(layer "B.Fab")
		)
		(fp_line
			(start -0.494 0.25)
			(end 0.504 0.25)
			(stroke
				(width 0.15)
				(type solid)
			)
			(layer "B.Fab")
		)
		(fp_line
			(start 0.504 -0.248)
			(end -0.494 -0.248)
			(stroke
				(width 0.15)
				(type solid)
			)
			(layer "B.Fab")
		)
		(fp_line
			(start 0.504 0.25)
			(end 0.504 -0.248)
			(stroke
				(width 0.15)
				(type solid)
			)
			(layer "B.Fab")
		)
		(fp_text user "${REFERENCE}"
			(at -0.939 -4.599 180)
			(layer "B.Fab")
			(effects
				(font
					(size 0.7 0.7)
					(thickness 0.15)
				)
				(justify left bottom mirror)
			)
		)
		(fp_text user "Author: Antmicro"
			(at -0.939 -3.399 180)
			(layer "B.Fab")
			(effects
				(font
					(size 0.7 0.7)
					(thickness 0.15)
				)
				(justify left bottom mirror)
			)
		)
		(fp_text user "License: Apache-2.0"
			(at -0.939 -5.799 180)
			(layer "B.Fab")
			(effects
				(font
					(size 0.7 0.7)
					(thickness 0.15)
				)
				(justify left bottom mirror)
			)
		)
		(pad "1" smd roundrect
			(at -0.48 0)
			(size 0.59 0.64)
			(layers "B.Cu" "B.Mask" "B.Paste")
			(roundrect_rratio 0.25)
			(net 23 "GND")
			(pintype "passive")
		)
		(pad "2" smd roundrect
			(at 0.48 0)
			(size 0.59 0.64)
			(layers "B.Cu" "B.Mask" "B.Paste")
			(roundrect_rratio 0.25)
			(net 134 "/2xRJ45/P1_CT")
			(pintype "passive")
		)
	)
)
